(kicad_pcb
	(version 20260206)
	(generator "pcbnew")
	(generator_version "10.0")
	(general
		(thickness 1.6)
		(legacy_teardrops no)
	)
	(paper "A4")
	(title_block
		(title "Bryce Canyon_R.DPB_16317-1_OCP.brd")
		(comment 1 "Bryce Canyon / footprints 1602-1605 of 2099")
	)
	(layers
		(0 "F.Cu" signal "TOP")
		(4 "In1.Cu" signal "L2GND")
		(6 "In2.Cu" signal "L3")
		(8 "In3.Cu" signal "L4VCC")
		(10 "In4.Cu" signal "L5VCC")
		(12 "In5.Cu" signal "L6")
		(14 "In6.Cu" signal "L7GND")
		(2 "B.Cu" signal "BOTTOM")
		(9 "F.Adhes" user "F.Adhesive")
		(11 "B.Adhes" user "B.Adhesive")
		(13 "F.Paste" user "Package Geometry/Pastemask Top")
		(15 "B.Paste" user "Package Geometry/Pastemask Bottom")
		(5 "F.SilkS" user "Ref Des/Silkscreen Top")
		(7 "B.SilkS" user "Ref Des/Silkscreen Bottom")
		(1 "F.Mask" user "Board Geometry/Soldermask Top")
		(3 "B.Mask" user "Board Geometry/Soldermask Bottom")
		(17 "Dwgs.User" user "User.Drawings")
		(19 "Cmts.User" user "User.Comments")
		(21 "Eco1.User" user "User.Eco1")
		(23 "Eco2.User" user "User.Eco2")
		(25 "Edge.Cuts" user "Board Geometry/Outline")
		(27 "Margin" user)
		(31 "F.CrtYd" user "Package Geometry/Place Bound Top")
		(29 "B.CrtYd" user "Package Geometry/Place Bound Bottom")
		(35 "F.Fab" user "Ref Des/Assembly Top")
		(33 "B.Fab" user "Ref Des/Assembly Bottom")
	)
	(footprint ""
		(layer "F.Cu")
		(at 338.709 -258.826 90)
		(property "Reference" "C117"
			(at 0 0 90)
			(layer "F.SilkS")
			(hide yes)
			(effects
				(font
					(size 1.27 1.27)
				)
			)
		)
		(property "Value" "SCD033U25V2KX-GP"
			(at 1.1811 -2.7051 90)
			(unlocked yes)
			(layer "F.Fab")
			(hide yes)
			(effects
				(font
					(size 1.016 1.016)
					(thickness 0.1524)
				)
			)
		)
		(property "Device Type" "C402H22"
			(at 1.1811 -4.2291 90)
			(unlocked yes)
			(layer "F.Fab")
			(hide yes)
			(effects
				(font
					(size 1.016 1.016)
					(thickness 0.1524)
				)
			)
		)
		(duplicate_pad_numbers_are_jumpers no)
		(fp_rect
			(start -0.4318 0.9525)
			(end 0.4318 -0.9525)
			(stroke
				(width 0)
				(type default)
			)
			(fill no)
			(layer "F.CrtYd")
		)
		(fp_rect
			(start -0.4318 0.9525)
			(end 0.4318 -0.9525)
			(stroke
				(width 0)
				(type default)
			)
			(fill no)
			(layer "F.Fab")
		)
		(pad "1" smd custom
			(at 0 -0.4445 90)
			(size 0.1524 0.1524)
			(layers "F.Cu" "F.Mask" "F.Paste")
			(net "P12V_B")
			(options
				(clearance outline)
				(anchor circle)
			)
			(primitives
				(gr_poly
					(pts
						(arc
							(start 0.3048 -0.2032)
							(mid 0.275042 -0.275042)
							(end 0.2032 -0.3048)
						)
						(arc
							(start -0.2032 -0.3048)
							(mid -0.275042 -0.275042)
							(end -0.3048 -0.2032)
						)
						(arc
							(start -0.3048 0.2032)
							(mid -0.275042 0.275042)
							(end -0.2032 0.3048)
						)
						(arc
							(start 0.2032 0.3048)
							(mid 0.275042 0.275042)
							(end 0.3048 0.2032)
						)
					)
					(width 0)
					(fill yes)
				)
			)
		)
		(pad "2" smd custom
			(at 0 0.4445 90)
			(size 0.1524 0.1524)
			(layers "F.Cu" "F.Mask" "F.Paste")
			(net "SW_HDD_N6")
			(options
				(clearance outline)
				(anchor circle)
			)
			(primitives
				(gr_poly
					(pts
						(arc
							(start 0.3048 -0.2032)
							(mid 0.275042 -0.275042)
							(end 0.2032 -0.3048)
						)
						(arc
							(start -0.2032 -0.3048)
							(mid -0.275042 -0.275042)
							(end -0.3048 -0.2032)
						)
						(arc
							(start -0.3048 0.2032)
							(mid -0.275042 0.275042)
							(end -0.2032 0.3048)
						)
						(arc
							(start 0.2032 0.3048)
							(mid 0.275042 0.275042)
							(end 0.3048 0.2032)
						)
					)
					(width 0)
					(fill yes)
				)
			)
		)
	)
	(footprint ""
		(layer "F.Cu")
		(at 169.47515 -102.351586 -90)
		(property "Reference" "R395"
			(at 0 0 270)
			(layer "F.SilkS")
			(hide yes)
			(effects
				(font
					(size 1.27 1.27)
				)
			)
		)
		(property "Value" "4K7R2F-GP"
			(at 0.064008 -3.993896 270)
			(unlocked yes)
			(layer "F.Fab")
			(hide yes)
			(effects
				(font
					(size 1.016 1.016)
					(thickness 0.1524)
				)
			)
		)
		(property "Device Type" "R402H16"
			(at 0.064008 -5.517896 270)
			(unlocked yes)
			(layer "F.Fab")
			(hide yes)
			(effects
				(font
					(size 1.016 1.016)
					(thickness 0.1524)
				)
			)
		)
		(duplicate_pad_numbers_are_jumpers no)
		(fp_line
			(start -0.508 -0.9398)
			(end -0.508 0.9398)
			(stroke
				(width 0.1524)
				(type default)
			)
			(layer "F.SilkS")
		)
		(fp_line
			(start 0.508 -0.9398)
			(end -0.508 -0.9398)
			(stroke
				(width 0.1524)
				(type default)
			)
			(layer "F.SilkS")
		)
		(fp_rect
			(start -0.508 0.9398)
			(end 0.508 -0.9398)
			(stroke
				(width 0)
				(type default)
			)
			(fill no)
			(layer "F.CrtYd")
		)
		(fp_rect
			(start -0.508 0.9398)
			(end 0.508 -0.9398)
			(stroke
				(width 0)
				(type default)
			)
			(fill no)
			(layer "F.Fab")
		)
		(pad "1" smd custom
			(at 0 -0.4445 270)
			(size 0.1397 0.1397)
			(layers "F.Cu" "F.Mask" "F.Paste")
			(net "DRIVE_B_17_FLT_LED")
			(options
				(clearance outline)
				(anchor circle)
			)
			(primitives
				(gr_poly
					(pts
						(arc
							(start -0.1778 -0.2794)
							(mid -0.249642 -0.249642)
							(end -0.2794 -0.1778)
						)
						(arc
							(start -0.2794 0.1778)
							(mid -0.249642 0.249642)
							(end -0.1778 0.2794)
						)
						(arc
							(start 0.1778 0.2794)
							(mid 0.249642 0.249642)
							(end 0.2794 0.1778)
						)
						(arc
							(start 0.2794 -0.1778)
							(mid 0.249642 -0.249642)
							(end 0.1778 -0.2794)
						)
					)
					(width 0)
					(fill yes)
				)
			)
		)
		(pad "2" smd custom
			(at 0 0.4445 270)
			(size 0.1397 0.1397)
			(layers "F.Cu" "F.Mask" "F.Paste")
			(net "GND")
			(options
				(clearance outline)
				(anchor circle)
			)
			(primitives
				(gr_poly
					(pts
						(arc
							(start -0.1778 -0.2794)
							(mid -0.249642 -0.249642)
							(end -0.2794 -0.1778)
						)
						(arc
							(start -0.2794 0.1778)
							(mid -0.249642 0.249642)
							(end -0.1778 0.2794)
						)
						(arc
							(start 0.1778 0.2794)
							(mid 0.249642 0.249642)
							(end 0.2794 0.1778)
						)
						(arc
							(start 0.2794 -0.1778)
							(mid 0.249642 -0.249642)
							(end 0.1778 -0.2794)
						)
					)
					(width 0)
					(fill yes)
				)
			)
		)
	)
	(footprint ""
		(layer "F.Cu")
		(at 20.1422 -263.7536 -90)
		(property "Reference" "C498"
			(at 0 0 270)
			(layer "F.SilkS")
			(hide yes)
			(effects
				(font
					(size 1.27 1.27)
				)
			)
		)
		(property "Value" "SC1U16V3KX-5GP"
			(at 0 -2.8194 270)
			(unlocked yes)
			(layer "F.Fab")
			(hide yes)
			(effects
				(font
					(size 1.016 1.016)
					(thickness 0.1524)
				)
			)
		)
		(property "Device Type" "C603H36"
			(at 0 -4.3434 270)
			(unlocked yes)
			(layer "F.Fab")
			(hide yes)
			(effects
				(font
					(size 1.016 1.016)
					(thickness 0.1524)
				)
			)
		)
		(duplicate_pad_numbers_are_jumpers no)
		(fp_line
			(start 0.508 0)
			(end -0.508 0)
			(stroke
				(width 0.2032)
				(type default)
			)
			(layer "F.SilkS")
		)
		(fp_rect
			(start -0.5842 1.3335)
			(end 0.5842 -1.3335)
			(stroke
				(width 0)
				(type default)
			)
			(fill no)
			(layer "F.CrtYd")
		)
		(fp_rect
			(start -0.5842 1.3335)
			(end 0.5842 -1.3335)
			(stroke
				(width 0)
				(type default)
			)
			(fill no)
			(layer "F.Fab")
		)
		(pad "1" smd custom
			(at 0 -0.762 270)
			(size 0.2159 0.2159)
			(layers "F.Cu" "F.Mask" "F.Paste")
			(net "P5V_HDD0")
			(options
				(clearance outline)
				(anchor circle)
			)
			(primitives
				(gr_poly
					(pts
						(arc
							(start -0.3302 -0.4318)
							(mid -0.402042 -0.402042)
							(end -0.4318 -0.3302)
						)
						(arc
							(start -0.4318 0.3302)
							(mid -0.402042 0.402042)
							(end -0.3302 0.4318)
						)
						(arc
							(start 0.3302 0.4318)
							(mid 0.402042 0.402042)
							(end 0.4318 0.3302)
						)
						(arc
							(start 0.4318 -0.3302)
							(mid 0.402042 -0.402042)
							(end 0.3302 -0.4318)
						)
					)
					(width 0)
					(fill yes)
				)
			)
		)
		(pad "2" smd custom
			(at 0 0.762 270)
			(size 0.2159 0.2159)
			(layers "F.Cu" "F.Mask" "F.Paste")
			(net "GND")
			(options
				(clearance outline)
				(anchor circle)
			)
			(primitives
				(gr_poly
					(pts
						(arc
							(start -0.3302 -0.4318)
							(mid -0.402042 -0.402042)
							(end -0.4318 -0.3302)
						)
						(arc
							(start -0.4318 0.3302)
							(mid -0.402042 0.402042)
							(end -0.3302 0.4318)
						)
						(arc
							(start 0.3302 0.4318)
							(mid 0.402042 0.402042)
							(end 0.4318 0.3302)
						)
						(arc
							(start 0.4318 -0.3302)
							(mid 0.402042 -0.402042)
							(end 0.3302 -0.4318)
						)
					)
					(width 0)
					(fill yes)
				)
			)
		)
	)
	(footprint ""
		(layer "F.Cu")
		(at 475.7166 -11.176)
		(property "Reference" "R885"
			(at 0 0 0)
			(layer "F.SilkS")
			(hide yes)
			(effects
				(font
					(size 1.27 1.27)
				)
			)
		)
		(property "Value" "0R2J-2-GP"
			(at 0.064008 -3.993896 0)
			(unlocked yes)
			(layer "F.Fab")
			(hide yes)
			(effects
				(font
					(size 1.016 1.016)
					(thickness 0.1524)
				)
			)
		)
		(property "Device Type" "R402H16"
			(at 0.064008 -5.517896 0)
			(unlocked yes)
			(layer "F.Fab")
			(hide yes)
			(effects
				(font
					(size 1.016 1.016)
					(thickness 0.1524)
				)
			)
		)
		(duplicate_pad_numbers_are_jumpers no)
		(fp_line
			(start -0.508 -0.9398)
			(end -0.508 0.9398)
			(stroke
				(width 0.1524)
				(type default)
			)
			(layer "F.SilkS")
		)
		(fp_line
			(start 0.508 -0.9398)
			(end -0.508 -0.9398)
			(stroke
				(width 0.1524)
				(type default)
			)
			(layer "F.SilkS")
		)
		(fp_rect
			(start -0.508 0.9398)
			(end 0.508 -0.9398)
			(stroke
				(width 0)
				(type default)
			)
			(fill no)
			(layer "F.CrtYd")
		)
		(fp_rect
			(start -0.508 0.9398)
			(end 0.508 -0.9398)
			(stroke
				(width 0)
				(type default)
			)
			(fill no)
			(layer "F.Fab")
		)
		(pad "1" smd custom
			(at 0 -0.4445)
			(size 0.1397 0.1397)
			(layers "F.Cu" "F.Mask" "F.Paste")
			(net "DRIVE_B_35_PWR")
			(options
				(clearance outline)
				(anchor circle)
			)
			(primitives
				(gr_poly
					(pts
						(arc
							(start -0.1778 -0.2794)
							(mid -0.249642 -0.249642)
							(end -0.2794 -0.1778)
						)
						(arc
							(start -0.2794 0.1778)
							(mid -0.249642 0.249642)
							(end -0.1778 0.2794)
						)
						(arc
							(start 0.1778 0.2794)
							(mid 0.249642 0.249642)
							(end 0.2794 0.1778)
						)
						(arc
							(start 0.2794 -0.1778)
							(mid 0.249642 -0.249642)
							(end 0.1778 -0.2794)
						)
					)
					(width 0)
					(fill yes)
				)
			)
		)
		(pad "2" smd custom
			(at 0 0.4445)
			(size 0.1397 0.1397)
			(layers "F.Cu" "F.Mask" "F.Paste")
			(net "SW_PWR_R_HDD35")
			(options
				(clearance outline)
				(anchor circle)
			)
			(primitives
				(gr_poly
					(pts
						(arc
							(start -0.1778 -0.2794)
							(mid -0.249642 -0.249642)
							(end -0.2794 -0.1778)
						)
						(arc
							(start -0.2794 0.1778)
							(mid -0.249642 0.249642)
							(end -0.1778 0.2794)
						)
						(arc
							(start 0.1778 0.2794)
							(mid 0.249642 0.249642)
							(end 0.2794 0.1778)
						)
						(arc
							(start 0.2794 -0.1778)
							(mid 0.249642 -0.249642)
							(end 0.1778 -0.2794)
						)
					)
					(width 0)
					(fill yes)
				)
			)
		)
	)
)
